(kicad_pcb
	(version 20260206)
	(generator "pcbnew")
	(generator_version "10.0")
	(general
		(thickness 1.6)
		(legacy_teardrops no)
	)
	(paper "A4")
	(title_block
		(title "04192023_DAF0TMB3IC0_F0TG_MB_C_brd_V02_OCP.brd")
		(comment 1 "Grand Teton / footprint 3955 of 8354 (U25), pads 5229-5337 of 6102")
	)
	(layers
		(0 "F.Cu" signal "TOP")
		(4 "In1.Cu" signal "GND")
		(6 "In2.Cu" signal "IN1")
		(8 "In3.Cu" signal "GND1")
		(10 "In4.Cu" signal "IN2")
		(12 "In5.Cu" signal "GND2")
		(14 "In6.Cu" signal "IN3")
		(16 "In7.Cu" signal "GND3")
		(18 "In8.Cu" signal "VCC")
		(20 "In9.Cu" signal "VCC1")
		(22 "In10.Cu" signal "GND4")
		(24 "In11.Cu" signal "IN4")
		(26 "In12.Cu" signal "GND5")
		(28 "In13.Cu" signal "IN5")
		(30 "In14.Cu" signal "GND6")
		(32 "In15.Cu" signal "IN6")
		(34 "In16.Cu" signal "GND7")
		(2 "B.Cu" signal "BOTTOM")
		(9 "F.Adhes" user "F.Adhesive")
		(11 "B.Adhes" user "B.Adhesive")
		(13 "F.Paste" user "Package Geometry/Pastemask Top")
		(15 "B.Paste" user "Package Geometry/Pastemask Bottom")
		(5 "F.SilkS" user "Ref Des/Silkscreen Top")
		(7 "B.SilkS" user "Ref Des/Silkscreen Bottom")
		(1 "F.Mask" user "Board Geometry/Soldermask Top")
		(3 "B.Mask" user "Board Geometry/Soldermask Bottom")
		(17 "Dwgs.User" user "User.Drawings")
		(19 "Cmts.User" user "User.Comments")
		(21 "Eco1.User" user "User.Eco1")
		(23 "Eco2.User" user "User.Eco2")
		(25 "Edge.Cuts" user "Board Geometry/Outline")
		(27 "Margin" user)
		(31 "F.CrtYd" user "Package Geometry/Place Bound Top")
		(29 "B.CrtYd" user "Package Geometry/Place Bound Bottom")
		(35 "F.Fab" user "Ref Des/Assembly Top")
		(33 "B.Fab" user "Ref Des/Assembly Bottom")
	)
	(footprint ""
		(layer "F.Cu")
		(at 359.867962 -258.880102 180)
		(property "Reference" "U25"
			(at -45.78477 -62.086744 0)
			(unlocked yes)
			(layer "F.SilkS")
			(effects
				(font
					(size 0.7874 0.5842)
					(thickness 0.1524)
				)
			)
		)
		(property "Value" ""
			(at 0 0 180)
			(layer "F.Fab")
			(effects
				(font
					(size 1.27 1.27)
				)
			)
		)
		(duplicate_pad_numbers_are_jumpers no)
		(pad "H65" smd circle
			(at 25.530048 -31.139892 180)
			(size 0.450088 0.450088)
			(layers "F.Cu" "F.Mask" "F.Paste")
			(net "M_F_CPU0_SA_DQS_DN<5>")
		)
		(pad "H66" smd circle
			(at 26.470102 -31.139892 180)
			(size 0.450088 0.450088)
			(layers "F.Cu" "F.Mask" "F.Paste")
			(net "GND")
		)
		(pad "H67" smd circle
			(at 27.409902 -31.139892 180)
			(size 0.450088 0.450088)
			(layers "F.Cu" "F.Mask" "F.Paste")
			(net "M_F_CPU0_SA_DQS_DN<0>")
		)
		(pad "H68" smd circle
			(at 28.349956 -31.139892 180)
			(size 0.450088 0.450088)
			(layers "F.Cu" "F.Mask" "F.Paste")
			(net "GND")
		)
		(pad "H69" smd circle
			(at 29.29001 -31.139892 180)
			(size 0.450088 0.450088)
			(layers "F.Cu" "F.Mask" "F.Paste")
			(net "M_E_CPU0_SA_DQS_DN<5>")
		)
		(pad "H70" smd circle
			(at 30.230064 -31.139892 180)
			(size 0.450088 0.450088)
			(layers "F.Cu" "F.Mask" "F.Paste")
			(net "M_E_CPU0_SA_DQS_DN<0>")
		)
		(pad "H71" smd circle
			(at 31.170118 -31.139892 180)
			(size 0.450088 0.450088)
			(layers "F.Cu" "F.Mask" "F.Paste")
			(net "PVDDIO_P0")
		)
		(pad "H72" smd circle
			(at 32.109918 -31.139892 180)
			(size 0.450088 0.450088)
			(layers "F.Cu" "F.Mask" "F.Paste")
			(net "M_A_CPU0_SA_DQS_DN<5>")
		)
		(pad "H73" smd circle
			(at 33.049972 -31.139892 180)
			(size 0.450088 0.450088)
			(layers "F.Cu" "F.Mask" "F.Paste")
			(net "GND")
		)
		(pad "H74" smd circle
			(at 33.990026 -31.139892 180)
			(size 0.450088 0.450088)
			(layers "F.Cu" "F.Mask" "F.Paste")
			(net "M_A_CPU0_SA_DQS_DN<0>")
		)
		(pad "J1" smd circle
			(at -34.159952 -30.329886 180)
			(size 0.450088 0.450088)
			(layers "F.Cu" "F.Mask" "F.Paste")
			(net "GND")
		)
		(pad "J2" smd circle
			(at -33.219898 -30.329886 180)
			(size 0.450088 0.450088)
			(layers "F.Cu" "F.Mask" "F.Paste")
			(net "M_G_CPU0_SA_DQ<4>")
		)
		(pad "J3" smd circle
			(at -32.280098 -30.329886 180)
			(size 0.450088 0.450088)
			(layers "F.Cu" "F.Mask" "F.Paste")
			(net "M_G_CPU0_SA_DQS_DP<5>")
		)
		(pad "J4" smd circle
			(at -31.340044 -30.329886 180)
			(size 0.450088 0.450088)
			(layers "F.Cu" "F.Mask" "F.Paste")
			(net "GND")
		)
		(pad "J5" smd circle
			(at -30.39999 -30.329886 180)
			(size 0.450088 0.450088)
			(layers "F.Cu" "F.Mask" "F.Paste")
			(net "M_K_CPU0_SA_DQ<4>")
		)
		(pad "J6" smd circle
			(at -29.459936 -30.329886 180)
			(size 0.450088 0.450088)
			(layers "F.Cu" "F.Mask" "F.Paste")
			(net "GND")
		)
		(pad "J7" smd circle
			(at -28.519882 -30.329886 180)
			(size 0.450088 0.450088)
			(layers "F.Cu" "F.Mask" "F.Paste")
			(net "M_K_CPU0_SA_DQS_DP<5>")
		)
		(pad "J8" smd circle
			(at -27.580082 -30.329886 180)
			(size 0.450088 0.450088)
			(layers "F.Cu" "F.Mask" "F.Paste")
			(net "GND")
		)
		(pad "J9" smd circle
			(at -26.640028 -30.329886 180)
			(size 0.450088 0.450088)
			(layers "F.Cu" "F.Mask" "F.Paste")
			(net "M_L_CPU0_SA_DQ<4>")
		)
		(pad "J10" smd circle
			(at -25.699974 -30.329886 180)
			(size 0.450088 0.450088)
			(layers "F.Cu" "F.Mask" "F.Paste")
			(net "M_L_CPU0_SA_DQS_DP<5>")
		)
		(pad "J11" smd circle
			(at -24.75992 -30.329886 180)
			(size 0.450088 0.450088)
			(layers "F.Cu" "F.Mask" "F.Paste")
			(net "GND")
		)
		(pad "J12" smd circle
			(at -23.82012 -30.329886 180)
			(size 0.450088 0.450088)
			(layers "F.Cu" "F.Mask" "F.Paste")
			(net "M_H_CPU0_SA_DQ<4>")
		)
		(pad "J13" smd circle
			(at -22.880066 -30.329886 180)
			(size 0.450088 0.450088)
			(layers "F.Cu" "F.Mask" "F.Paste")
			(net "GND")
		)
		(pad "J14" smd circle
			(at -21.940012 -30.329886 180)
			(size 0.450088 0.450088)
			(layers "F.Cu" "F.Mask" "F.Paste")
			(net "M_H_CPU0_SA_DQS_DP<5>")
		)
		(pad "J15" smd circle
			(at -20.999958 -30.329886 180)
			(size 0.450088 0.450088)
			(layers "F.Cu" "F.Mask" "F.Paste")
			(net "GND")
		)
		(pad "J16" smd circle
			(at -20.059904 -30.329886 180)
			(size 0.450088 0.450088)
			(layers "F.Cu" "F.Mask" "F.Paste")
			(net "M_J_CPU0_SA_DQ<4>")
		)
		(pad "J17" smd circle
			(at -19.120104 -30.329886 180)
			(size 0.450088 0.450088)
			(layers "F.Cu" "F.Mask" "F.Paste")
			(net "M_J_CPU0_SA_DQS_DP<5>")
		)
		(pad "J18" smd circle
			(at -18.18005 -30.329886 180)
			(size 0.450088 0.450088)
			(layers "F.Cu" "F.Mask" "F.Paste")
			(net "GND")
		)
		(pad "J19" smd circle
			(at -17.239996 -30.329886 180)
			(size 0.450088 0.450088)
			(layers "F.Cu" "F.Mask" "F.Paste")
			(net "M_I_CPU0_SA_DQ<4>")
		)
		(pad "J20" smd circle
			(at -16.299942 -30.329886 180)
			(size 0.450088 0.450088)
			(layers "F.Cu" "F.Mask" "F.Paste")
			(net "GND")
		)
		(pad "J21" smd circle
			(at -15.359888 -30.329886 180)
			(size 0.450088 0.450088)
			(layers "F.Cu" "F.Mask" "F.Paste")
			(net "M_I_CPU0_SA_DQS_DP<5>")
		)
		(pad "J22" smd circle
			(at -14.420088 -30.329886 180)
			(size 0.450088 0.450088)
			(layers "F.Cu" "F.Mask" "F.Paste")
			(net "GND")
		)
		(pad "J23" smd circle
			(at -13.480034 -30.329886 180)
			(size 0.450088 0.450088)
			(layers "F.Cu" "F.Mask" "F.Paste")
			(net "GMI_CPU0_G2_CPU1_G0_TX_DP<1>")
		)
		(pad "J24" smd circle
			(at -12.53998 -30.329886 180)
			(size 0.450088 0.450088)
			(layers "F.Cu" "F.Mask" "F.Paste")
			(net "GMI_CPU0_G2_CPU1_G0_TX_DN<1>")
		)
		(pad "J25" smd circle
			(at -11.599926 -30.329886 180)
			(size 0.450088 0.450088)
			(layers "F.Cu" "F.Mask" "F.Paste")
			(net "GND")
		)
		(pad "J26" smd circle
			(at -10.659872 -30.329886 180)
			(size 0.450088 0.450088)
			(layers "F.Cu" "F.Mask" "F.Paste")
			(net "GMI_CPU0_G2_CPU1_G0_TX_DP<4>")
		)
		(pad "J27" smd circle
			(at -9.720072 -30.329886 180)
			(size 0.450088 0.450088)
			(layers "F.Cu" "F.Mask" "F.Paste")
			(net "GMI_CPU0_G2_CPU1_G0_TX_DN<4>")
		)
		(pad "J28" smd circle
			(at -8.780018 -30.329886 180)
			(size 0.450088 0.450088)
			(layers "F.Cu" "F.Mask" "F.Paste")
			(net "GND")
		)
		(pad "J29" smd circle
			(at -7.839964 -30.329886 180)
			(size 0.450088 0.450088)
			(layers "F.Cu" "F.Mask" "F.Paste")
			(net "GMI_CPU0_G2_CPU1_G0_TX_DP<7>")
		)
		(pad "J30" smd circle
			(at -6.89991 -30.329886 180)
			(size 0.450088 0.450088)
			(layers "F.Cu" "F.Mask" "F.Paste")
			(net "GMI_CPU0_G2_CPU1_G0_TX_DN<7>")
		)
		(pad "J31" smd circle
			(at -5.96011 -30.329886 180)
			(size 0.450088 0.450088)
			(layers "F.Cu" "F.Mask" "F.Paste")
			(net "GND")
		)
		(pad "J32" smd circle
			(at -5.020056 -30.329886 180)
			(size 0.450088 0.450088)
			(layers "F.Cu" "F.Mask" "F.Paste")
			(net "GMI_CPU0_G2_CPU1_G0_TX_DP<10>")
		)
		(pad "J33" smd circle
			(at -4.080002 -30.329886 180)
			(size 0.450088 0.450088)
			(layers "F.Cu" "F.Mask" "F.Paste")
			(net "GMI_CPU0_G2_CPU1_G0_TX_DN<10>")
		)
		(pad "J34" smd circle
			(at -3.139948 -30.329886 180)
			(size 0.450088 0.450088)
			(layers "F.Cu" "F.Mask" "F.Paste")
			(net "GND")
		)
		(pad "J35" smd circle
			(at -2.199894 -30.329886 180)
			(size 0.450088 0.450088)
			(layers "F.Cu" "F.Mask" "F.Paste")
			(net "PVDDCR_CPU0_P0")
		)
		(pad "J36" smd circle
			(at -1.260094 -30.329886 180)
			(size 0.450088 0.450088)
			(layers "F.Cu" "F.Mask" "F.Paste")
			(net "PVDDCR_CPU0_P0")
		)
		(pad "J40" smd circle
			(at 1.560068 -30.329886 180)
			(size 0.450088 0.450088)
			(layers "F.Cu" "F.Mask" "F.Paste")
			(net "PVDDCR_CPU0_P0")
		)
		(pad "J41" smd circle
			(at 2.500122 -30.329886 180)
			(size 0.450088 0.450088)
			(layers "F.Cu" "F.Mask" "F.Paste")
			(net "PVDDCR_CPU0_P0")
		)
		(pad "J42" smd circle
			(at 3.439922 -30.329886 180)
			(size 0.450088 0.450088)
			(layers "F.Cu" "F.Mask" "F.Paste")
			(net "GND")
		)
		(pad "J43" smd circle
			(at 4.379976 -30.329886 180)
			(size 0.450088 0.450088)
			(layers "F.Cu" "F.Mask" "F.Paste")
			(net "GMI_CPU1_G2_CPU0_G0_TX_DN<5>")
		)
		(pad "J44" smd circle
			(at 5.32003 -30.329886 180)
			(size 0.450088 0.450088)
			(layers "F.Cu" "F.Mask" "F.Paste")
			(net "GMI_CPU1_G2_CPU0_G0_TX_DP<5>")
		)
		(pad "J45" smd circle
			(at 6.260084 -30.329886 180)
			(size 0.450088 0.450088)
			(layers "F.Cu" "F.Mask" "F.Paste")
			(net "GND")
		)
		(pad "J46" smd circle
			(at 7.199884 -30.329886 180)
			(size 0.450088 0.450088)
			(layers "F.Cu" "F.Mask" "F.Paste")
			(net "GMI_CPU1_G2_CPU0_G0_TX_DN<8>")
		)
		(pad "J47" smd circle
			(at 8.139938 -30.329886 180)
			(size 0.450088 0.450088)
			(layers "F.Cu" "F.Mask" "F.Paste")
			(net "GMI_CPU1_G2_CPU0_G0_TX_DP<8>")
		)
		(pad "J48" smd circle
			(at 9.079992 -30.329886 180)
			(size 0.450088 0.450088)
			(layers "F.Cu" "F.Mask" "F.Paste")
			(net "GND")
		)
		(pad "J49" smd circle
			(at 10.020046 -30.329886 180)
			(size 0.450088 0.450088)
			(layers "F.Cu" "F.Mask" "F.Paste")
			(net "GMI_CPU1_G2_CPU0_G0_TX_DN<11>")
		)
		(pad "J50" smd circle
			(at 10.9601 -30.329886 180)
			(size 0.450088 0.450088)
			(layers "F.Cu" "F.Mask" "F.Paste")
			(net "GMI_CPU1_G2_CPU0_G0_TX_DP<11>")
		)
		(pad "J51" smd circle
			(at 11.8999 -30.329886 180)
			(size 0.450088 0.450088)
			(layers "F.Cu" "F.Mask" "F.Paste")
			(net "GND")
		)
		(pad "J52" smd circle
			(at 12.839954 -30.329886 180)
			(size 0.450088 0.450088)
			(layers "F.Cu" "F.Mask" "F.Paste")
			(net "GMI_CPU1_G2_CPU0_G0_TX_DN<14>")
		)
		(pad "J53" smd circle
			(at 13.780008 -30.329886 180)
			(size 0.450088 0.450088)
			(layers "F.Cu" "F.Mask" "F.Paste")
			(net "GMI_CPU1_G2_CPU0_G0_TX_DP<14>")
		)
		(pad "J54" smd circle
			(at 14.720062 -30.329886 180)
			(size 0.450088 0.450088)
			(layers "F.Cu" "F.Mask" "F.Paste")
			(net "GND")
		)
		(pad "J55" smd circle
			(at 15.660116 -30.329886 180)
			(size 0.450088 0.450088)
			(layers "F.Cu" "F.Mask" "F.Paste")
			(net "M_C_CPU0_SA_DQS_DP<5>")
		)
		(pad "J56" smd circle
			(at 16.599916 -30.329886 180)
			(size 0.450088 0.450088)
			(layers "F.Cu" "F.Mask" "F.Paste")
			(net "GND")
		)
		(pad "J57" smd circle
			(at 17.53997 -30.329886 180)
			(size 0.450088 0.450088)
			(layers "F.Cu" "F.Mask" "F.Paste")
			(net "M_C_CPU0_SA_DQ<4>")
		)
		(pad "J58" smd circle
			(at 18.480024 -30.329886 180)
			(size 0.450088 0.450088)
			(layers "F.Cu" "F.Mask" "F.Paste")
			(net "GND")
		)
		(pad "J59" smd circle
			(at 19.420078 -30.329886 180)
			(size 0.450088 0.450088)
			(layers "F.Cu" "F.Mask" "F.Paste")
			(net "M_D_CPU0_SA_DQS_DP<5>")
		)
		(pad "J60" smd circle
			(at 20.359878 -30.329886 180)
			(size 0.450088 0.450088)
			(layers "F.Cu" "F.Mask" "F.Paste")
			(net "M_D_CPU0_SA_DQ<4>")
		)
		(pad "J61" smd circle
			(at 21.299932 -30.329886 180)
			(size 0.450088 0.450088)
			(layers "F.Cu" "F.Mask" "F.Paste")
			(net "GND")
		)
		(pad "J62" smd circle
			(at 22.239986 -30.329886 180)
			(size 0.450088 0.450088)
			(layers "F.Cu" "F.Mask" "F.Paste")
			(net "M_B_CPU0_SA_DQS_DP<5>")
		)
		(pad "J63" smd circle
			(at 23.18004 -30.329886 180)
			(size 0.450088 0.450088)
			(layers "F.Cu" "F.Mask" "F.Paste")
			(net "GND")
		)
		(pad "J64" smd circle
			(at 24.120094 -30.329886 180)
			(size 0.450088 0.450088)
			(layers "F.Cu" "F.Mask" "F.Paste")
			(net "M_B_CPU0_SA_DQ<4>")
		)
		(pad "J65" smd circle
			(at 25.059894 -30.329886 180)
			(size 0.450088 0.450088)
			(layers "F.Cu" "F.Mask" "F.Paste")
			(net "GND")
		)
		(pad "J66" smd circle
			(at 25.999948 -30.329886 180)
			(size 0.450088 0.450088)
			(layers "F.Cu" "F.Mask" "F.Paste")
			(net "M_F_CPU0_SA_DQS_DP<5>")
		)
		(pad "J67" smd circle
			(at 26.940002 -30.329886 180)
			(size 0.450088 0.450088)
			(layers "F.Cu" "F.Mask" "F.Paste")
			(net "M_F_CPU0_SA_DQ<4>")
		)
		(pad "J68" smd circle
			(at 27.880056 -30.329886 180)
			(size 0.450088 0.450088)
			(layers "F.Cu" "F.Mask" "F.Paste")
			(net "GND")
		)
		(pad "J69" smd circle
			(at 28.82011 -30.329886 180)
			(size 0.450088 0.450088)
			(layers "F.Cu" "F.Mask" "F.Paste")
			(net "M_E_CPU0_SA_DQS_DP<5>")
		)
		(pad "J70" smd circle
			(at 29.75991 -30.329886 180)
			(size 0.450088 0.450088)
			(layers "F.Cu" "F.Mask" "F.Paste")
			(net "GND")
		)
		(pad "J71" smd circle
			(at 30.699964 -30.329886 180)
			(size 0.450088 0.450088)
			(layers "F.Cu" "F.Mask" "F.Paste")
			(net "M_E_CPU0_SA_DQ<4>")
		)
		(pad "J72" smd circle
			(at 31.640018 -30.329886 180)
			(size 0.450088 0.450088)
			(layers "F.Cu" "F.Mask" "F.Paste")
			(net "GND")
		)
		(pad "J73" smd circle
			(at 32.580072 -30.329886 180)
			(size 0.450088 0.450088)
			(layers "F.Cu" "F.Mask" "F.Paste")
			(net "M_A_CPU0_SA_DQS_DP<5>")
		)
		(pad "J74" smd circle
			(at 33.519872 -30.329886 180)
			(size 0.450088 0.450088)
			(layers "F.Cu" "F.Mask" "F.Paste")
			(net "M_A_CPU0_SA_DQ<4>")
		)
		(pad "J75" smd circle
			(at 34.459926 -30.329886 180)
			(size 0.450088 0.450088)
			(layers "F.Cu" "F.Mask" "F.Paste")
			(net "GND")
		)
		(pad "K2" smd circle
			(at -33.690052 -29.51988 180)
			(size 0.450088 0.450088)
			(layers "F.Cu" "F.Mask" "F.Paste")
			(net "M_G_CPU0_SA_DQ<6>")
		)
		(pad "K3" smd circle
			(at -32.749998 -29.51988 180)
			(size 0.450088 0.450088)
			(layers "F.Cu" "F.Mask" "F.Paste")
			(net "GND")
		)
		(pad "K4" smd circle
			(at -31.809944 -29.51988 180)
			(size 0.450088 0.450088)
			(layers "F.Cu" "F.Mask" "F.Paste")
			(net "M_G_CPU0_SA_DQ<5>")
		)
		(pad "K5" smd circle
			(at -30.86989 -29.51988 180)
			(size 0.450088 0.450088)
			(layers "F.Cu" "F.Mask" "F.Paste")
			(net "GND")
		)
		(pad "K6" smd circle
			(at -29.93009 -29.51988 180)
			(size 0.450088 0.450088)
			(layers "F.Cu" "F.Mask" "F.Paste")
			(net "M_K_CPU0_SA_DQ<6>")
		)
		(pad "K7" smd circle
			(at -28.990036 -29.51988 180)
			(size 0.450088 0.450088)
			(layers "F.Cu" "F.Mask" "F.Paste")
			(net "M_K_CPU0_SA_DQ<5>")
		)
		(pad "K8" smd circle
			(at -28.049982 -29.51988 180)
			(size 0.450088 0.450088)
			(layers "F.Cu" "F.Mask" "F.Paste")
			(net "GND")
		)
		(pad "K9" smd circle
			(at -27.109928 -29.51988 180)
			(size 0.450088 0.450088)
			(layers "F.Cu" "F.Mask" "F.Paste")
			(net "M_L_CPU0_SA_DQ<6>")
		)
		(pad "K10" smd circle
			(at -26.170128 -29.51988 180)
			(size 0.450088 0.450088)
			(layers "F.Cu" "F.Mask" "F.Paste")
			(net "GND")
		)
		(pad "K11" smd circle
			(at -25.230074 -29.51988 180)
			(size 0.450088 0.450088)
			(layers "F.Cu" "F.Mask" "F.Paste")
			(net "M_L_CPU0_SA_DQ<5>")
		)
		(pad "K12" smd circle
			(at -24.29002 -29.51988 180)
			(size 0.450088 0.450088)
			(layers "F.Cu" "F.Mask" "F.Paste")
			(net "GND")
		)
		(pad "K13" smd circle
			(at -23.349966 -29.51988 180)
			(size 0.450088 0.450088)
			(layers "F.Cu" "F.Mask" "F.Paste")
			(net "M_H_CPU0_SA_DQ<6>")
		)
		(pad "K14" smd circle
			(at -22.409912 -29.51988 180)
			(size 0.450088 0.450088)
			(layers "F.Cu" "F.Mask" "F.Paste")
			(net "M_H_CPU0_SA_DQ<5>")
		)
		(pad "K15" smd circle
			(at -21.470112 -29.51988 180)
			(size 0.450088 0.450088)
			(layers "F.Cu" "F.Mask" "F.Paste")
			(net "GND")
		)
		(pad "K16" smd circle
			(at -20.530058 -29.51988 180)
			(size 0.450088 0.450088)
			(layers "F.Cu" "F.Mask" "F.Paste")
			(net "M_J_CPU0_SA_DQ<6>")
		)
		(pad "K17" smd circle
			(at -19.590004 -29.51988 180)
			(size 0.450088 0.450088)
			(layers "F.Cu" "F.Mask" "F.Paste")
			(net "GND")
		)
		(pad "K18" smd circle
			(at -18.64995 -29.51988 180)
			(size 0.450088 0.450088)
			(layers "F.Cu" "F.Mask" "F.Paste")
			(net "M_J_CPU0_SA_DQ<5>")
		)
		(pad "K19" smd circle
			(at -17.709896 -29.51988 180)
			(size 0.450088 0.450088)
			(layers "F.Cu" "F.Mask" "F.Paste")
			(net "GND")
		)
		(pad "K20" smd circle
			(at -16.770096 -29.51988 180)
			(size 0.450088 0.450088)
			(layers "F.Cu" "F.Mask" "F.Paste")
			(net "M_I_CPU0_SA_DQ<6>")
		)
		(pad "K21" smd circle
			(at -15.830042 -29.51988 180)
			(size 0.450088 0.450088)
			(layers "F.Cu" "F.Mask" "F.Paste")
			(net "M_I_CPU0_SA_DQ<5>")
		)
		(pad "K22" smd circle
			(at -14.889988 -29.51988 180)
			(size 0.450088 0.450088)
			(layers "F.Cu" "F.Mask" "F.Paste")
			(net "PVDDCR_SOC_P0")
		)
		(pad "K23" smd circle
			(at -13.949934 -29.51988 180)
			(size 0.450088 0.450088)
			(layers "F.Cu" "F.Mask" "F.Paste")
			(net "GND")
		)
		(pad "K24" smd circle
			(at -13.00988 -29.51988 180)
			(size 0.450088 0.450088)
			(layers "F.Cu" "F.Mask" "F.Paste")
			(net "GND")
		)
		(pad "K25" smd circle
			(at -12.07008 -29.51988 180)
			(size 0.450088 0.450088)
			(layers "F.Cu" "F.Mask" "F.Paste")
			(net "GND")
		)
		(pad "K26" smd circle
			(at -11.130026 -29.51988 180)
			(size 0.450088 0.450088)
			(layers "F.Cu" "F.Mask" "F.Paste")
			(net "GND")
		)
		(pad "K27" smd circle
			(at -10.189972 -29.51988 180)
			(size 0.450088 0.450088)
			(layers "F.Cu" "F.Mask" "F.Paste")
			(net "GND")
		)
		(pad "K28" smd circle
			(at -9.249918 -29.51988 180)
			(size 0.450088 0.450088)
			(layers "F.Cu" "F.Mask" "F.Paste")
			(net "GND")
		)
	)
)
